(kicad_pcb
	(version 20260206)
	(generator "pcbnew")
	(generator_version "10.0")
	(general
		(thickness 1.6)
		(legacy_teardrops no)
	)
	(paper "A4")
	(title_block
		(title "04192023_DAF0TMB3IC0_F0TG_MB_C_brd_V02_OCP.brd")
		(comment 1 "Grand Teton / footprints 240-247 of 8354")
	)
	(layers
		(0 "F.Cu" signal "TOP")
		(4 "In1.Cu" signal "GND")
		(6 "In2.Cu" signal "IN1")
		(8 "In3.Cu" signal "GND1")
		(10 "In4.Cu" signal "IN2")
		(12 "In5.Cu" signal "GND2")
		(14 "In6.Cu" signal "IN3")
		(16 "In7.Cu" signal "GND3")
		(18 "In8.Cu" signal "VCC")
		(20 "In9.Cu" signal "VCC1")
		(22 "In10.Cu" signal "GND4")
		(24 "In11.Cu" signal "IN4")
		(26 "In12.Cu" signal "GND5")
		(28 "In13.Cu" signal "IN5")
		(30 "In14.Cu" signal "GND6")
		(32 "In15.Cu" signal "IN6")
		(34 "In16.Cu" signal "GND7")
		(2 "B.Cu" signal "BOTTOM")
		(9 "F.Adhes" user "F.Adhesive")
		(11 "B.Adhes" user "B.Adhesive")
		(13 "F.Paste" user "Package Geometry/Pastemask Top")
		(15 "B.Paste" user "Package Geometry/Pastemask Bottom")
		(5 "F.SilkS" user "Ref Des/Silkscreen Top")
		(7 "B.SilkS" user "Ref Des/Silkscreen Bottom")
		(1 "F.Mask" user "Board Geometry/Soldermask Top")
		(3 "B.Mask" user "Board Geometry/Soldermask Bottom")
		(17 "Dwgs.User" user "User.Drawings")
		(19 "Cmts.User" user "User.Comments")
		(21 "Eco1.User" user "User.Eco1")
		(23 "Eco2.User" user "User.Eco2")
		(25 "Edge.Cuts" user "Board Geometry/Outline")
		(27 "Margin" user)
		(31 "F.CrtYd" user "Package Geometry/Place Bound Top")
		(29 "B.CrtYd" user "Package Geometry/Place Bound Bottom")
		(35 "F.Fab" user "Ref Des/Assembly Top")
		(33 "B.Fab" user "Ref Des/Assembly Bottom")
	)
	(footprint ""
		(layer "F.Cu")
		(at 68.212462 -40.437562)
		(property "Reference" "R3608"
			(at 0 0 0)
			(layer "F.SilkS")
			(hide yes)
			(effects
				(font
					(size 1.27 1.27)
				)
			)
		)
		(property "Value" ""
			(at 0 0 0)
			(layer "F.Fab")
			(effects
				(font
					(size 1.27 1.27)
				)
			)
		)
		(duplicate_pad_numbers_are_jumpers no)
		(fp_line
			(start -0.7874 -0.4064)
			(end 0.7874 -0.4064)
			(stroke
				(width 0.1524)
				(type default)
			)
			(layer "F.SilkS")
		)
		(fp_line
			(start -0.7874 0.4064)
			(end -0.7874 -0.4064)
			(stroke
				(width 0.1524)
				(type default)
			)
			(layer "F.SilkS")
		)
		(fp_line
			(start 0.7874 -0.4064)
			(end 0.7874 0.4064)
			(stroke
				(width 0.1524)
				(type default)
			)
			(layer "F.SilkS")
		)
		(fp_line
			(start 0.7874 0.4064)
			(end -0.7874 0.4064)
			(stroke
				(width 0.1524)
				(type default)
			)
			(layer "F.SilkS")
		)
		(fp_line
			(start -0.67945 -0.305054)
			(end -0.12065 -0.305054)
			(stroke
				(width 0.1)
				(type default)
			)
			(layer "F.Fab")
		)
		(fp_line
			(start -0.67945 0.3048)
			(end -0.67945 -0.305054)
			(stroke
				(width 0.1)
				(type default)
			)
			(layer "F.Fab")
		)
		(fp_line
			(start -0.12065 -0.305054)
			(end -0.12065 -0.2794)
			(stroke
				(width 0.1)
				(type default)
			)
			(layer "F.Fab")
		)
		(fp_line
			(start -0.12065 -0.2794)
			(end 0.12065 -0.2794)
			(stroke
				(width 0.1)
				(type default)
			)
			(layer "F.Fab")
		)
		(fp_line
			(start -0.12065 0.2794)
			(end -0.12065 0.3048)
			(stroke
				(width 0.1)
				(type default)
			)
			(layer "F.Fab")
		)
		(fp_line
			(start -0.12065 0.3048)
			(end -0.67945 0.3048)
			(stroke
				(width 0.1)
				(type default)
			)
			(layer "F.Fab")
		)
		(fp_line
			(start 0.120396 0.2794)
			(end -0.12065 0.2794)
			(stroke
				(width 0.1)
				(type default)
			)
			(layer "F.Fab")
		)
		(fp_line
			(start 0.120396 0.3048)
			(end 0.120396 0.2794)
			(stroke
				(width 0.1)
				(type default)
			)
			(layer "F.Fab")
		)
		(fp_line
			(start 0.12065 -0.3048)
			(end 0.67945 -0.3048)
			(stroke
				(width 0.1)
				(type default)
			)
			(layer "F.Fab")
		)
		(fp_line
			(start 0.12065 -0.2794)
			(end 0.12065 -0.3048)
			(stroke
				(width 0.1)
				(type default)
			)
			(layer "F.Fab")
		)
		(fp_line
			(start 0.67945 -0.3048)
			(end 0.67945 0.3048)
			(stroke
				(width 0.1)
				(type default)
			)
			(layer "F.Fab")
		)
		(fp_line
			(start 0.67945 0.3048)
			(end 0.120396 0.3048)
			(stroke
				(width 0.1)
				(type default)
			)
			(layer "F.Fab")
		)
		(pad "1" smd circle
			(at -0.40005 0)
			(size 0 0)
			(layers "F.Cu" "F.Mask" "F.Paste")
			(net "GND")
		)
		(pad "2" smd circle
			(at 0.40005 0)
			(size 0 0)
			(layers "F.Cu" "F.Mask" "F.Paste")
			(net "INA230_3_A1")
		)
	)
	(footprint ""
		(layer "F.Cu")
		(at 325.697342 -399.12798)
		(property "Reference" "R1364"
			(at 0 0 0)
			(layer "F.SilkS")
			(hide yes)
			(effects
				(font
					(size 1.27 1.27)
				)
			)
		)
		(property "Value" ""
			(at 0 0 0)
			(layer "F.Fab")
			(effects
				(font
					(size 1.27 1.27)
				)
			)
		)
		(duplicate_pad_numbers_are_jumpers no)
		(fp_line
			(start -0.32512 -0.175006)
			(end 0.32512 -0.175006)
			(stroke
				(width 0.1)
				(type default)
			)
			(layer "F.Fab")
		)
		(fp_line
			(start -0.32512 0.175006)
			(end -0.32512 -0.175006)
			(stroke
				(width 0.1)
				(type default)
			)
			(layer "F.Fab")
		)
		(fp_line
			(start 0.32512 -0.175006)
			(end 0.32512 0.175006)
			(stroke
				(width 0.1)
				(type default)
			)
			(layer "F.Fab")
		)
		(fp_line
			(start 0.32512 0.175006)
			(end -0.32512 0.175006)
			(stroke
				(width 0.1)
				(type default)
			)
			(layer "F.Fab")
		)
		(pad "1" smd rect
			(at -0.2667 0)
			(size 0.3048 0.381)
			(layers "F.Cu" "F.Mask" "F.Paste")
			(net "JTAG_TRST_RT_CPU0_P0_N")
		)
		(pad "2" smd rect
			(at 0.2667 0 180)
			(size 0.3048 0.381)
			(layers "F.Cu" "F.Mask" "F.Paste")
			(net "GND")
		)
	)
	(footprint ""
		(layer "F.Cu")
		(at 372.109492 -383.88163 -90)
		(property "Reference" "C892"
			(at 0 0 270)
			(layer "F.SilkS")
			(hide yes)
			(effects
				(font
					(size 1.27 1.27)
				)
			)
		)
		(property "Value" ""
			(at 0 0 270)
			(layer "F.Fab")
			(effects
				(font
					(size 1.27 1.27)
				)
			)
		)
		(duplicate_pad_numbers_are_jumpers no)
		(fp_line
			(start -0.299974 0.150114)
			(end -0.299974 -0.150114)
			(stroke
				(width 0.1)
				(type default)
			)
			(layer "F.Fab")
		)
		(fp_line
			(start 0.299974 0.150114)
			(end -0.299974 0.150114)
			(stroke
				(width 0.1)
				(type default)
			)
			(layer "F.Fab")
		)
		(fp_line
			(start -0.299974 -0.150114)
			(end 0.299974 -0.150114)
			(stroke
				(width 0.1)
				(type default)
			)
			(layer "F.Fab")
		)
		(fp_line
			(start 0.299974 -0.150114)
			(end 0.299974 0.150114)
			(stroke
				(width 0.1)
				(type default)
			)
			(layer "F.Fab")
		)
		(pad "1" smd rect
			(at -0.2667 0 270)
			(size 0.3048 0.381)
			(layers "F.Cu" "F.Mask" "F.Paste")
			(net "P5E_CPU0_P3_TX_C_DN<4>")
		)
		(pad "2" smd rect
			(at 0.2667 0 270)
			(size 0.3048 0.381)
			(layers "F.Cu" "F.Mask" "F.Paste")
			(net "P5E_CPU0_P3_TX_DN<4>")
		)
	)
	(footprint ""
		(layer "F.Cu")
		(at 355.08057 -402.7424 -90)
		(property "Reference" "R1041"
			(at 0 0 270)
			(layer "F.SilkS")
			(hide yes)
			(effects
				(font
					(size 1.27 1.27)
				)
			)
		)
		(property "Value" ""
			(at 0 0 270)
			(layer "F.Fab")
			(effects
				(font
					(size 1.27 1.27)
				)
			)
		)
		(duplicate_pad_numbers_are_jumpers no)
		(fp_line
			(start -0.32512 0.175006)
			(end -0.32512 -0.175006)
			(stroke
				(width 0.1)
				(type default)
			)
			(layer "F.Fab")
		)
		(fp_line
			(start 0.32512 0.175006)
			(end -0.32512 0.175006)
			(stroke
				(width 0.1)
				(type default)
			)
			(layer "F.Fab")
		)
		(fp_line
			(start -0.32512 -0.175006)
			(end 0.32512 -0.175006)
			(stroke
				(width 0.1)
				(type default)
			)
			(layer "F.Fab")
		)
		(fp_line
			(start 0.32512 -0.175006)
			(end 0.32512 0.175006)
			(stroke
				(width 0.1)
				(type default)
			)
			(layer "F.Fab")
		)
		(pad "1" smd rect
			(at -0.2667 0 270)
			(size 0.3048 0.381)
			(layers "F.Cu" "F.Mask" "F.Paste")
			(net "RT_CPU0_P1_VQPS")
		)
		(pad "2" smd rect
			(at 0.2667 0 90)
			(size 0.3048 0.381)
			(layers "F.Cu" "F.Mask" "F.Paste")
			(net "GND")
		)
	)
	(footprint ""
		(layer "F.Cu")
		(at 385.749038 -182.661052 90)
		(property "Reference" "PC553_4"
			(at 0 0 90)
			(layer "F.SilkS")
			(hide yes)
			(effects
				(font
					(size 1.27 1.27)
				)
			)
		)
		(property "Value" ""
			(at 0 0 90)
			(layer "F.Fab")
			(effects
				(font
					(size 1.27 1.27)
				)
			)
		)
		(duplicate_pad_numbers_are_jumpers no)
		(fp_line
			(start 0.7874 -0.4064)
			(end 0.7874 0.4064)
			(stroke
				(width 0.1524)
				(type default)
			)
			(layer "F.SilkS")
		)
		(fp_line
			(start -0.7874 -0.4064)
			(end 0.7874 -0.4064)
			(stroke
				(width 0.1524)
				(type default)
			)
			(layer "F.SilkS")
		)
		(fp_line
			(start 0.7874 0.4064)
			(end -0.7874 0.4064)
			(stroke
				(width 0.1524)
				(type default)
			)
			(layer "F.SilkS")
		)
		(fp_line
			(start -0.7874 0.4064)
			(end -0.7874 -0.4064)
			(stroke
				(width 0.1524)
				(type default)
			)
			(layer "F.SilkS")
		)
		(fp_line
			(start -0.12065 -0.305054)
			(end -0.12065 -0.2794)
			(stroke
				(width 0.1)
				(type default)
			)
			(layer "F.Fab")
		)
		(fp_line
			(start -0.67945 -0.305054)
			(end -0.12065 -0.305054)
			(stroke
				(width 0.1)
				(type default)
			)
			(layer "F.Fab")
		)
		(fp_line
			(start 0.67945 -0.3048)
			(end 0.67945 0.3048)
			(stroke
				(width 0.1)
				(type default)
			)
			(layer "F.Fab")
		)
		(fp_line
			(start 0.12065 -0.3048)
			(end 0.67945 -0.3048)
			(stroke
				(width 0.1)
				(type default)
			)
			(layer "F.Fab")
		)
		(fp_line
			(start 0.12065 -0.2794)
			(end 0.12065 -0.3048)
			(stroke
				(width 0.1)
				(type default)
			)
			(layer "F.Fab")
		)
		(fp_line
			(start -0.12065 -0.2794)
			(end 0.12065 -0.2794)
			(stroke
				(width 0.1)
				(type default)
			)
			(layer "F.Fab")
		)
		(fp_line
			(start 0.120396 0.2794)
			(end -0.12065 0.2794)
			(stroke
				(width 0.1)
				(type default)
			)
			(layer "F.Fab")
		)
		(fp_line
			(start -0.12065 0.2794)
			(end -0.12065 0.3048)
			(stroke
				(width 0.1)
				(type default)
			)
			(layer "F.Fab")
		)
		(fp_line
			(start 0.67945 0.3048)
			(end 0.120396 0.3048)
			(stroke
				(width 0.1)
				(type default)
			)
			(layer "F.Fab")
		)
		(fp_line
			(start 0.120396 0.3048)
			(end 0.120396 0.2794)
			(stroke
				(width 0.1)
				(type default)
			)
			(layer "F.Fab")
		)
		(fp_line
			(start -0.12065 0.3048)
			(end -0.67945 0.3048)
			(stroke
				(width 0.1)
				(type default)
			)
			(layer "F.Fab")
		)
		(fp_line
			(start -0.67945 0.3048)
			(end -0.67945 -0.305054)
			(stroke
				(width 0.1)
				(type default)
			)
			(layer "F.Fab")
		)
		(pad "1" smd circle
			(at -0.40005 0 90)
			(size 0 0)
			(layers "F.Cu" "F.Mask" "F.Paste")
			(net "SW_P12V_AUX_PVDDCR_CPU0_P0_FLT")
		)
		(pad "2" smd circle
			(at 0.40005 0 90)
			(size 0 0)
			(layers "F.Cu" "F.Mask" "F.Paste")
			(net "GND")
		)
	)
	(footprint ""
		(layer "F.Cu")
		(at 314.567316 -109.53877 180)
		(property "Reference" "R24"
			(at 0 0 180)
			(layer "F.SilkS")
			(hide yes)
			(effects
				(font
					(size 1.27 1.27)
				)
			)
		)
		(property "Value" ""
			(at 0 0 180)
			(layer "F.Fab")
			(effects
				(font
					(size 1.27 1.27)
				)
			)
		)
		(duplicate_pad_numbers_are_jumpers no)
		(fp_line
			(start 0.7874 0.4064)
			(end -0.7874 0.4064)
			(stroke
				(width 0.1524)
				(type default)
			)
			(layer "F.SilkS")
		)
		(fp_line
			(start 0.7874 -0.4064)
			(end 0.7874 0.4064)
			(stroke
				(width 0.1524)
				(type default)
			)
			(layer "F.SilkS")
		)
		(fp_line
			(start -0.7874 0.4064)
			(end -0.7874 -0.4064)
			(stroke
				(width 0.1524)
				(type default)
			)
			(layer "F.SilkS")
		)
		(fp_line
			(start -0.7874 -0.4064)
			(end 0.7874 -0.4064)
			(stroke
				(width 0.1524)
				(type default)
			)
			(layer "F.SilkS")
		)
		(fp_line
			(start 0.67945 0.3048)
			(end 0.120396 0.3048)
			(stroke
				(width 0.1)
				(type default)
			)
			(layer "F.Fab")
		)
		(fp_line
			(start 0.67945 -0.3048)
			(end 0.67945 0.3048)
			(stroke
				(width 0.1)
				(type default)
			)
			(layer "F.Fab")
		)
		(fp_line
			(start 0.12065 -0.2794)
			(end 0.12065 -0.3048)
			(stroke
				(width 0.1)
				(type default)
			)
			(layer "F.Fab")
		)
		(fp_line
			(start 0.12065 -0.3048)
			(end 0.67945 -0.3048)
			(stroke
				(width 0.1)
				(type default)
			)
			(layer "F.Fab")
		)
		(fp_line
			(start 0.120396 0.3048)
			(end 0.120396 0.2794)
			(stroke
				(width 0.1)
				(type default)
			)
			(layer "F.Fab")
		)
		(fp_line
			(start 0.120396 0.2794)
			(end -0.12065 0.2794)
			(stroke
				(width 0.1)
				(type default)
			)
			(layer "F.Fab")
		)
		(fp_line
			(start -0.12065 0.3048)
			(end -0.67945 0.3048)
			(stroke
				(width 0.1)
				(type default)
			)
			(layer "F.Fab")
		)
		(fp_line
			(start -0.12065 0.2794)
			(end -0.12065 0.3048)
			(stroke
				(width 0.1)
				(type default)
			)
			(layer "F.Fab")
		)
		(fp_line
			(start -0.12065 -0.2794)
			(end 0.12065 -0.2794)
			(stroke
				(width 0.1)
				(type default)
			)
			(layer "F.Fab")
		)
		(fp_line
			(start -0.12065 -0.305054)
			(end -0.12065 -0.2794)
			(stroke
				(width 0.1)
				(type default)
			)
			(layer "F.Fab")
		)
		(fp_line
			(start -0.67945 0.3048)
			(end -0.67945 -0.305054)
			(stroke
				(width 0.1)
				(type default)
			)
			(layer "F.Fab")
		)
		(fp_line
			(start -0.67945 -0.305054)
			(end -0.12065 -0.305054)
			(stroke
				(width 0.1)
				(type default)
			)
			(layer "F.Fab")
		)
		(pad "1" smd circle
			(at -0.40005 0 180)
			(size 0 0)
			(layers "F.Cu" "F.Mask" "F.Paste")
			(net "P3V3_AUX")
		)
		(pad "2" smd circle
			(at 0.40005 0 180)
			(size 0 0)
			(layers "F.Cu" "F.Mask" "F.Paste")
			(net "SMB_CPU_FRU_3V3AUX_SDA")
		)
	)
	(footprint ""
		(layer "F.Cu")
		(at 251.474224 -134.892796)
		(property "Reference" "R1547"
			(at 0 0 0)
			(layer "F.SilkS")
			(hide yes)
			(effects
				(font
					(size 1.27 1.27)
				)
			)
		)
		(property "Value" ""
			(at 0 0 0)
			(layer "F.Fab")
			(effects
				(font
					(size 1.27 1.27)
				)
			)
		)
		(duplicate_pad_numbers_are_jumpers no)
		(fp_line
			(start -0.7874 -0.4064)
			(end 0.7874 -0.4064)
			(stroke
				(width 0.1524)
				(type default)
			)
			(layer "F.SilkS")
		)
		(fp_line
			(start -0.7874 0.4064)
			(end -0.7874 -0.4064)
			(stroke
				(width 0.1524)
				(type default)
			)
			(layer "F.SilkS")
		)
		(fp_line
			(start 0.7874 -0.4064)
			(end 0.7874 0.4064)
			(stroke
				(width 0.1524)
				(type default)
			)
			(layer "F.SilkS")
		)
		(fp_line
			(start 0.7874 0.4064)
			(end -0.7874 0.4064)
			(stroke
				(width 0.1524)
				(type default)
			)
			(layer "F.SilkS")
		)
		(fp_line
			(start -0.67945 -0.305054)
			(end -0.12065 -0.305054)
			(stroke
				(width 0.1)
				(type default)
			)
			(layer "F.Fab")
		)
		(fp_line
			(start -0.67945 0.3048)
			(end -0.67945 -0.305054)
			(stroke
				(width 0.1)
				(type default)
			)
			(layer "F.Fab")
		)
		(fp_line
			(start -0.12065 -0.305054)
			(end -0.12065 -0.2794)
			(stroke
				(width 0.1)
				(type default)
			)
			(layer "F.Fab")
		)
		(fp_line
			(start -0.12065 -0.2794)
			(end 0.12065 -0.2794)
			(stroke
				(width 0.1)
				(type default)
			)
			(layer "F.Fab")
		)
		(fp_line
			(start -0.12065 0.2794)
			(end -0.12065 0.3048)
			(stroke
				(width 0.1)
				(type default)
			)
			(layer "F.Fab")
		)
		(fp_line
			(start -0.12065 0.3048)
			(end -0.67945 0.3048)
			(stroke
				(width 0.1)
				(type default)
			)
			(layer "F.Fab")
		)
		(fp_line
			(start 0.120396 0.2794)
			(end -0.12065 0.2794)
			(stroke
				(width 0.1)
				(type default)
			)
			(layer "F.Fab")
		)
		(fp_line
			(start 0.120396 0.3048)
			(end 0.120396 0.2794)
			(stroke
				(width 0.1)
				(type default)
			)
			(layer "F.Fab")
		)
		(fp_line
			(start 0.12065 -0.3048)
			(end 0.67945 -0.3048)
			(stroke
				(width 0.1)
				(type default)
			)
			(layer "F.Fab")
		)
		(fp_line
			(start 0.12065 -0.2794)
			(end 0.12065 -0.3048)
			(stroke
				(width 0.1)
				(type default)
			)
			(layer "F.Fab")
		)
		(fp_line
			(start 0.67945 -0.3048)
			(end 0.67945 0.3048)
			(stroke
				(width 0.1)
				(type default)
			)
			(layer "F.Fab")
		)
		(fp_line
			(start 0.67945 0.3048)
			(end 0.120396 0.3048)
			(stroke
				(width 0.1)
				(type default)
			)
			(layer "F.Fab")
		)
		(pad "1" smd circle
			(at -0.40005 0)
			(size 0 0)
			(layers "F.Cu" "F.Mask" "F.Paste")
			(net "P3V3_AUX")
		)
		(pad "2" smd circle
			(at 0.40005 0)
			(size 0 0)
			(layers "F.Cu" "F.Mask" "F.Paste")
			(net "SPI_CPU0_LVC3_TPM_CS_N")
		)
	)
	(footprint ""
		(layer "F.Cu")
		(at 216.408 -123.825 90)
		(property "Reference" "R9033"
			(at 0 0 90)
			(layer "F.SilkS")
			(hide yes)
			(effects
				(font
					(size 1.27 1.27)
				)
			)
		)
		(property "Value" ""
			(at 0 0 90)
			(layer "F.Fab")
			(effects
				(font
					(size 1.27 1.27)
				)
			)
		)
		(duplicate_pad_numbers_are_jumpers no)
		(fp_line
			(start 0.7874 -0.4064)
			(end 0.7874 0.4064)
			(stroke
				(width 0.1524)
				(type default)
			)
			(layer "F.SilkS")
		)
		(fp_line
			(start -0.7874 -0.4064)
			(end 0.7874 -0.4064)
			(stroke
				(width 0.1524)
				(type default)
			)
			(layer "F.SilkS")
		)
		(fp_line
			(start 0.7874 0.4064)
			(end -0.7874 0.4064)
			(stroke
				(width 0.1524)
				(type default)
			)
			(layer "F.SilkS")
		)
		(fp_line
			(start -0.7874 0.4064)
			(end -0.7874 -0.4064)
			(stroke
				(width 0.1524)
				(type default)
			)
			(layer "F.SilkS")
		)
		(fp_line
			(start -0.12065 -0.305054)
			(end -0.12065 -0.2794)
			(stroke
				(width 0.1)
				(type default)
			)
			(layer "F.Fab")
		)
		(fp_line
			(start -0.67945 -0.305054)
			(end -0.12065 -0.305054)
			(stroke
				(width 0.1)
				(type default)
			)
			(layer "F.Fab")
		)
		(fp_line
			(start 0.67945 -0.3048)
			(end 0.67945 0.3048)
			(stroke
				(width 0.1)
				(type default)
			)
			(layer "F.Fab")
		)
		(fp_line
			(start 0.12065 -0.3048)
			(end 0.67945 -0.3048)
			(stroke
				(width 0.1)
				(type default)
			)
			(layer "F.Fab")
		)
		(fp_line
			(start 0.12065 -0.2794)
			(end 0.12065 -0.3048)
			(stroke
				(width 0.1)
				(type default)
			)
			(layer "F.Fab")
		)
		(fp_line
			(start -0.12065 -0.2794)
			(end 0.12065 -0.2794)
			(stroke
				(width 0.1)
				(type default)
			)
			(layer "F.Fab")
		)
		(fp_line
			(start 0.120396 0.2794)
			(end -0.12065 0.2794)
			(stroke
				(width 0.1)
				(type default)
			)
			(layer "F.Fab")
		)
		(fp_line
			(start -0.12065 0.2794)
			(end -0.12065 0.3048)
			(stroke
				(width 0.1)
				(type default)
			)
			(layer "F.Fab")
		)
		(fp_line
			(start 0.67945 0.3048)
			(end 0.120396 0.3048)
			(stroke
				(width 0.1)
				(type default)
			)
			(layer "F.Fab")
		)
		(fp_line
			(start 0.120396 0.3048)
			(end 0.120396 0.2794)
			(stroke
				(width 0.1)
				(type default)
			)
			(layer "F.Fab")
		)
		(fp_line
			(start -0.12065 0.3048)
			(end -0.67945 0.3048)
			(stroke
				(width 0.1)
				(type default)
			)
			(layer "F.Fab")
		)
		(fp_line
			(start -0.67945 0.3048)
			(end -0.67945 -0.305054)
			(stroke
				(width 0.1)
				(type default)
			)
			(layer "F.Fab")
		)
		(pad "1" smd circle
			(at -0.40005 0 90)
			(size 0 0)
			(layers "F.Cu" "F.Mask" "F.Paste")
			(net "RST_PERST_OCP_SFF_BUF_R_N")
		)
		(pad "2" smd circle
			(at 0.40005 0 90)
			(size 0 0)
			(layers "F.Cu" "F.Mask" "F.Paste")
			(net "RST_PERST_OCP_SFF_BUF_N")
		)
	)
)
